(kicad_pcb
	(version 20260206)
	(generator "pcbnew")
	(generator_version "10.0")
	(general
		(thickness 1.6)
		(legacy_teardrops no)
	)
	(paper "A4")
	(title_block
		(title "baseboard — 13948-1b.1110WZS1818.brd")
		(comment 1 "Honey Badger (Wiwynn) / footprints 1043-1049 of 2523")
	)
	(layers
		(0 "F.Cu" signal "TOP")
		(4 "In1.Cu" signal "L2GND")
		(6 "In2.Cu" signal "L3")
		(8 "In3.Cu" signal "L4VCC")
		(10 "In4.Cu" signal "L5VCC")
		(12 "In5.Cu" signal "L6")
		(14 "In6.Cu" signal "L7GND")
		(2 "B.Cu" signal "BOTTOM")
		(9 "F.Adhes" user "F.Adhesive")
		(11 "B.Adhes" user "B.Adhesive")
		(13 "F.Paste" user "Package Geometry/Pastemask Top")
		(15 "B.Paste" user "Package Geometry/Pastemask Bottom")
		(5 "F.SilkS" user "Ref Des/Silkscreen Top")
		(7 "B.SilkS" user "Ref Des/Silkscreen Bottom")
		(1 "F.Mask" user "Board Geometry/Soldermask Top")
		(3 "B.Mask" user "Board Geometry/Soldermask Bottom")
		(17 "Dwgs.User" user "User.Drawings")
		(19 "Cmts.User" user "User.Comments")
		(21 "Eco1.User" user "User.Eco1")
		(23 "Eco2.User" user "User.Eco2")
		(25 "Edge.Cuts" user "Board Geometry/Outline")
		(27 "Margin" user)
		(31 "F.CrtYd" user "Package Geometry/Place Bound Top")
		(29 "B.CrtYd" user "Package Geometry/Place Bound Bottom")
		(35 "F.Fab" user "Ref Des/Assembly Top")
		(33 "B.Fab" user "Ref Des/Assembly Bottom")
	)
	(footprint ""
		(layer "F.Cu")
		(at 95.358966 -63.119)
		(property "Reference" "SR676"
			(at 0 0 0)
			(layer "F.SilkS")
			(hide yes)
			(effects
				(font
					(size 1.27 1.27)
				)
			)
		)
		(property "Value" "4K7R2F-GP"
			(at 0.064008 -3.993896 0)
			(unlocked yes)
			(layer "F.Fab")
			(hide yes)
			(effects
				(font
					(size 1.016 1.016)
					(thickness 0.1524)
				)
			)
		)
		(property "Device Type" "R402H16"
			(at 0.064008 -5.517896 0)
			(unlocked yes)
			(layer "F.Fab")
			(hide yes)
			(effects
				(font
					(size 1.016 1.016)
					(thickness 0.1524)
				)
			)
		)
		(duplicate_pad_numbers_are_jumpers no)
		(fp_line
			(start -0.508 -0.9398)
			(end -0.508 0.9398)
			(stroke
				(width 0.1524)
				(type default)
			)
			(layer "F.SilkS")
		)
		(fp_line
			(start 0.508 -0.9398)
			(end -0.508 -0.9398)
			(stroke
				(width 0.1524)
				(type default)
			)
			(layer "F.SilkS")
		)
		(fp_rect
			(start -0.508 0.9398)
			(end 0.508 -0.9398)
			(stroke
				(width 0)
				(type default)
			)
			(fill no)
			(layer "F.CrtYd")
		)
		(fp_rect
			(start -0.508 0.9398)
			(end 0.508 -0.9398)
			(stroke
				(width 0)
				(type default)
			)
			(fill no)
			(layer "F.Fab")
		)
		(pad "1" smd custom
			(at 0 -0.4445)
			(size 0.1397 0.1397)
			(layers "F.Cu" "F.Mask" "F.Paste")
			(net "P1V8_C")
			(options
				(clearance outline)
				(anchor circle)
			)
			(primitives
				(gr_poly
					(pts
						(arc
							(start -0.1778 -0.2794)
							(mid -0.249642 -0.249642)
							(end -0.2794 -0.1778)
						)
						(arc
							(start -0.2794 0.1778)
							(mid -0.249642 0.249642)
							(end -0.1778 0.2794)
						)
						(arc
							(start 0.1778 0.2794)
							(mid 0.249642 0.249642)
							(end 0.2794 0.1778)
						)
						(arc
							(start 0.2794 -0.1778)
							(mid 0.249642 -0.249642)
							(end 0.1778 -0.2794)
						)
					)
					(width 0)
					(fill yes)
				)
			)
		)
		(pad "2" smd custom
			(at 0 0.4445)
			(size 0.1397 0.1397)
			(layers "F.Cu" "F.Mask" "F.Paste")
			(net "ICE0_TRST#")
			(options
				(clearance outline)
				(anchor circle)
			)
			(primitives
				(gr_poly
					(pts
						(arc
							(start -0.1778 -0.2794)
							(mid -0.249642 -0.249642)
							(end -0.2794 -0.1778)
						)
						(arc
							(start -0.2794 0.1778)
							(mid -0.249642 0.249642)
							(end -0.1778 0.2794)
						)
						(arc
							(start 0.1778 0.2794)
							(mid 0.249642 0.249642)
							(end 0.2794 0.1778)
						)
						(arc
							(start 0.2794 -0.1778)
							(mid 0.249642 -0.249642)
							(end 0.1778 -0.2794)
						)
					)
					(width 0)
					(fill yes)
				)
			)
		)
	)
	(footprint ""
		(layer "F.Cu")
		(at 333.912718 -142.217648 90)
		(property "Reference" "R223"
			(at 0 0 90)
			(layer "F.SilkS")
			(hide yes)
			(effects
				(font
					(size 1.27 1.27)
				)
			)
		)
		(property "Value" "4K7R2F-GP"
			(at 0.064008 -3.993896 90)
			(unlocked yes)
			(layer "F.Fab")
			(hide yes)
			(effects
				(font
					(size 1.016 1.016)
					(thickness 0.1524)
				)
			)
		)
		(property "Device Type" "R402H16"
			(at 0.064008 -5.517896 90)
			(unlocked yes)
			(layer "F.Fab")
			(hide yes)
			(effects
				(font
					(size 1.016 1.016)
					(thickness 0.1524)
				)
			)
		)
		(duplicate_pad_numbers_are_jumpers no)
		(fp_line
			(start 0.508 -0.9398)
			(end -0.508 -0.9398)
			(stroke
				(width 0.1524)
				(type default)
			)
			(layer "F.SilkS")
		)
		(fp_line
			(start -0.508 -0.9398)
			(end -0.508 0.9398)
			(stroke
				(width 0.1524)
				(type default)
			)
			(layer "F.SilkS")
		)
		(fp_rect
			(start -0.508 0.9398)
			(end 0.508 -0.9398)
			(stroke
				(width 0)
				(type default)
			)
			(fill no)
			(layer "F.CrtYd")
		)
		(fp_rect
			(start -0.508 0.9398)
			(end 0.508 -0.9398)
			(stroke
				(width 0)
				(type default)
			)
			(fill no)
			(layer "F.Fab")
		)
		(pad "1" smd custom
			(at 0 -0.4445 90)
			(size 0.1397 0.1397)
			(layers "F.Cu" "F.Mask" "F.Paste")
			(net "P3V3_STBY")
			(options
				(clearance outline)
				(anchor circle)
			)
			(primitives
				(gr_poly
					(pts
						(arc
							(start -0.1778 -0.2794)
							(mid -0.249642 -0.249642)
							(end -0.2794 -0.1778)
						)
						(arc
							(start -0.2794 0.1778)
							(mid -0.249642 0.249642)
							(end -0.1778 0.2794)
						)
						(arc
							(start 0.1778 0.2794)
							(mid 0.249642 0.249642)
							(end 0.2794 0.1778)
						)
						(arc
							(start 0.2794 -0.1778)
							(mid 0.249642 -0.249642)
							(end 0.1778 -0.2794)
						)
					)
					(width 0)
					(fill yes)
				)
			)
		)
		(pad "2" smd custom
			(at 0 0.4445 90)
			(size 0.1397 0.1397)
			(layers "F.Cu" "F.Mask" "F.Paste")
			(net "USB_SUSP_IND")
			(options
				(clearance outline)
				(anchor circle)
			)
			(primitives
				(gr_poly
					(pts
						(arc
							(start -0.1778 -0.2794)
							(mid -0.249642 -0.249642)
							(end -0.2794 -0.1778)
						)
						(arc
							(start -0.2794 0.1778)
							(mid -0.249642 0.249642)
							(end -0.1778 0.2794)
						)
						(arc
							(start 0.1778 0.2794)
							(mid 0.249642 0.249642)
							(end 0.2794 0.1778)
						)
						(arc
							(start 0.2794 -0.1778)
							(mid 0.249642 -0.249642)
							(end 0.1778 -0.2794)
						)
					)
					(width 0)
					(fill yes)
				)
			)
		)
	)
	(footprint ""
		(layer "F.Cu")
		(at 54.991 -103.251 -90)
		(property "Reference" "SCN8"
			(at 0 0 270)
			(layer "F.SilkS")
			(hide yes)
			(effects
				(font
					(size 1.27 1.27)
				)
			)
		)
		(property "Value" "JWT-CON4-S24-GP"
			(at -7.3787 1.4351 270)
			(unlocked yes)
			(layer "F.Fab")
			(hide yes)
			(effects
				(font
					(size 1.016 1.016)
					(thickness 0.1524)
				)
			)
		)
		(property "Device Type" "A2541WV0-1QX4PA-6T"
			(at -7.3787 -0.0889 270)
			(unlocked yes)
			(layer "F.Fab")
			(hide yes)
			(effects
				(font
					(size 1.016 1.016)
					(thickness 0.1524)
				)
			)
		)
		(duplicate_pad_numbers_are_jumpers no)
		(fp_line
			(start -5.334 1.524)
			(end 5.334 1.524)
			(stroke
				(width 0.1524)
				(type default)
			)
			(layer "F.SilkS")
		)
		(fp_line
			(start 5.334 1.524)
			(end 5.334 -1.524)
			(stroke
				(width 0.1524)
				(type default)
			)
			(layer "F.SilkS")
		)
		(fp_line
			(start -5.334 -1.524)
			(end -5.334 1.524)
			(stroke
				(width 0.1524)
				(type default)
			)
			(layer "F.SilkS")
		)
		(fp_line
			(start 5.334 -1.524)
			(end -5.334 -1.524)
			(stroke
				(width 0.1524)
				(type default)
			)
			(layer "F.SilkS")
		)
		(fp_line
			(start -5.461 -1.651)
			(end -5.461 -0.381)
			(stroke
				(width 0.4064)
				(type default)
			)
			(layer "F.SilkS")
		)
		(fp_line
			(start -4.191 -1.651)
			(end -5.461 -1.651)
			(stroke
				(width 0.4064)
				(type default)
			)
			(layer "F.SilkS")
		)
		(fp_circle
			(center -3.81 0)
			(end -3.81 -1.0668)
			(stroke
				(width 0.3048)
				(type default)
			)
			(fill no)
			(layer "F.SilkS")
		)
		(fp_circle
			(center -1.27 0)
			(end -1.27 -1.0668)
			(stroke
				(width 0.3048)
				(type default)
			)
			(fill no)
			(layer "F.SilkS")
		)
		(fp_circle
			(center 1.27 0)
			(end 1.27 -1.0668)
			(stroke
				(width 0.3048)
				(type default)
			)
			(fill no)
			(layer "F.SilkS")
		)
		(fp_circle
			(center 3.81 0)
			(end 3.81 -1.0668)
			(stroke
				(width 0.3048)
				(type default)
			)
			(fill no)
			(layer "F.SilkS")
		)
		(fp_rect
			(start -5.08 1.27)
			(end 5.08 -1.27)
			(stroke
				(width 0)
				(type default)
			)
			(fill no)
			(layer "F.CrtYd")
		)
		(fp_poly
			(pts
				(xy -5.588 1.778) (xy -5.588 -1.778) (xy 5.588 -1.778) (xy 5.588 1.2573) (xy 5.08 1.2573) (xy 5.08 -1.27)
				(xy -5.08 -1.27) (xy -5.08 1.27) (xy 5.588 1.27) (xy 5.588 1.778)
			)
			(stroke
				(width 0)
				(type default)
			)
			(fill no)
			(layer "F.CrtYd")
		)
		(fp_rect
			(start -5.588 1.778)
			(end 5.588 -1.778)
			(stroke
				(width 0)
				(type default)
			)
			(fill no)
			(layer "F.Fab")
		)
		(pad "1" thru_hole circle
			(at -3.81 0 270)
			(size 1.4224 1.4224)
			(drill 1.016)
			(layers "*.Cu" "*.Mask")
			(remove_unused_layers no)
			(net "P5V_STBY")
			(clearance 0.1524)
			(thermal_gap 0.1524)
		)
		(pad "2" thru_hole circle
			(at -1.27 0 270)
			(size 1.4224 1.4224)
			(drill 1.016)
			(layers "*.Cu" "*.Mask")
			(remove_unused_layers no)
			(net "BMC_R_TXD5")
			(clearance 0.1524)
			(thermal_gap 0.1524)
		)
		(pad "3" thru_hole circle
			(at 1.27 0 270)
			(size 1.4224 1.4224)
			(drill 1.016)
			(layers "*.Cu" "*.Mask")
			(remove_unused_layers no)
			(net "BMC_R_RXD5")
			(clearance 0.1524)
			(thermal_gap 0.1524)
		)
		(pad "4" thru_hole circle
			(at 3.81 0 270)
			(size 1.4224 1.4224)
			(drill 1.016)
			(layers "*.Cu" "*.Mask")
			(remove_unused_layers no)
			(net "GND")
			(clearance 0.1524)
			(thermal_gap 0.1524)
		)
	)
	(footprint ""
		(layer "F.Cu")
		(at 187.442856 -143.138652 -90)
		(property "Reference" "R609"
			(at 0 0 270)
			(layer "F.SilkS")
			(hide yes)
			(effects
				(font
					(size 1.27 1.27)
				)
			)
		)
		(property "Value" "0R2J-2-GP"
			(at 0.064008 -3.993896 270)
			(unlocked yes)
			(layer "F.Fab")
			(hide yes)
			(effects
				(font
					(size 1.016 1.016)
					(thickness 0.1524)
				)
			)
		)
		(property "Device Type" "R402H16"
			(at 0.064008 -5.517896 270)
			(unlocked yes)
			(layer "F.Fab")
			(hide yes)
			(effects
				(font
					(size 1.016 1.016)
					(thickness 0.1524)
				)
			)
		)
		(duplicate_pad_numbers_are_jumpers no)
		(fp_line
			(start -0.508 -0.9398)
			(end -0.508 0.9398)
			(stroke
				(width 0.1524)
				(type default)
			)
			(layer "F.SilkS")
		)
		(fp_line
			(start 0.508 -0.9398)
			(end -0.508 -0.9398)
			(stroke
				(width 0.1524)
				(type default)
			)
			(layer "F.SilkS")
		)
		(fp_rect
			(start -0.508 0.9398)
			(end 0.508 -0.9398)
			(stroke
				(width 0)
				(type default)
			)
			(fill no)
			(layer "F.CrtYd")
		)
		(fp_rect
			(start -0.508 0.9398)
			(end 0.508 -0.9398)
			(stroke
				(width 0)
				(type default)
			)
			(fill no)
			(layer "F.Fab")
		)
		(pad "1" smd custom
			(at 0 -0.4445 270)
			(size 0.1397 0.1397)
			(layers "F.Cu" "F.Mask" "F.Paste")
			(net "EXP_EEPROM_SDA")
			(options
				(clearance outline)
				(anchor circle)
			)
			(primitives
				(gr_poly
					(pts
						(arc
							(start -0.1778 -0.2794)
							(mid -0.249642 -0.249642)
							(end -0.2794 -0.1778)
						)
						(arc
							(start -0.2794 0.1778)
							(mid -0.249642 0.249642)
							(end -0.1778 0.2794)
						)
						(arc
							(start 0.1778 0.2794)
							(mid 0.249642 0.249642)
							(end 0.2794 0.1778)
						)
						(arc
							(start 0.2794 -0.1778)
							(mid 0.249642 -0.249642)
							(end 0.1778 -0.2794)
						)
					)
					(width 0)
					(fill yes)
				)
			)
		)
		(pad "2" smd custom
			(at 0 0.4445 270)
			(size 0.1397 0.1397)
			(layers "F.Cu" "F.Mask" "F.Paste")
			(net "EXP_SDA_0")
			(options
				(clearance outline)
				(anchor circle)
			)
			(primitives
				(gr_poly
					(pts
						(arc
							(start -0.1778 -0.2794)
							(mid -0.249642 -0.249642)
							(end -0.2794 -0.1778)
						)
						(arc
							(start -0.2794 0.1778)
							(mid -0.249642 0.249642)
							(end -0.1778 0.2794)
						)
						(arc
							(start 0.1778 0.2794)
							(mid 0.249642 0.249642)
							(end 0.2794 0.1778)
						)
						(arc
							(start 0.2794 -0.1778)
							(mid 0.249642 -0.249642)
							(end 0.1778 -0.2794)
						)
					)
					(width 0)
					(fill yes)
				)
			)
		)
	)
	(footprint ""
		(layer "F.Cu")
		(at 305.562 -163.957)
		(property "Reference" "TP154"
			(at 0 0 0)
			(layer "F.SilkS")
			(hide yes)
			(effects
				(font
					(size 1.27 1.27)
				)
			)
		)
		(property "Value" "TPAD28"
			(at 0.0127 -1.8034 0)
			(unlocked yes)
			(layer "F.Fab")
			(hide yes)
			(effects
				(font
					(size 1.016 1.016)
					(thickness 0.1524)
				)
			)
		)
		(property "Device Type" "TPAD28"
			(at 0.0127 -3.3274 0)
			(unlocked yes)
			(layer "F.Fab")
			(hide yes)
			(effects
				(font
					(size 1.016 1.016)
					(thickness 0.1524)
				)
			)
		)
		(duplicate_pad_numbers_are_jumpers no)
		(fp_poly
			(pts
				(arc
					(start 0.3556 0)
					(mid -0.3556 0)
					(end 0.3556 0)
				)
			)
			(stroke
				(width 0)
				(type default)
			)
			(fill no)
			(layer "F.CrtYd")
		)
		(fp_poly
			(pts
				(arc
					(start 0.6096 0)
					(mid -0.6096 0)
					(end 0.6096 0)
				)
			)
			(stroke
				(width 0)
				(type default)
			)
			(fill no)
			(layer "F.Fab")
		)
		(pad "1" smd circle
			(at 0 0)
			(size 0.7112 0.7112)
			(layers "F.Cu" "F.Mask" "F.Paste")
			(net "TP_BMC_GPIOA6")
		)
	)
	(footprint ""
		(layer "F.Cu")
		(at 152.247092 -113.313464 -90)
		(property "Reference" "SR836"
			(at 0 0 270)
			(layer "F.SilkS")
			(hide yes)
			(effects
				(font
					(size 1.27 1.27)
				)
			)
		)
		(property "Value" "D51R3F-2-GP"
			(at -0.0254 -2.5146 270)
			(unlocked yes)
			(layer "F.Fab")
			(hide yes)
			(effects
				(font
					(size 1.016 1.016)
					(thickness 0.1524)
				)
			)
		)
		(property "Device Type" "R603H22"
			(at -0.0254 -4.0386 270)
			(unlocked yes)
			(layer "F.Fab")
			(hide yes)
			(effects
				(font
					(size 1.016 1.016)
					(thickness 0.1524)
				)
			)
		)
		(duplicate_pad_numbers_are_jumpers no)
		(fp_line
			(start -0.4826 0)
			(end -0.2032 0)
			(stroke
				(width 0.2032)
				(type default)
			)
			(layer "F.SilkS")
		)
		(fp_line
			(start 0.2032 0)
			(end 0.4826 0)
			(stroke
				(width 0.2032)
				(type default)
			)
			(layer "F.SilkS")
		)
		(fp_rect
			(start -0.5842 1.3335)
			(end 0.5842 -1.3335)
			(stroke
				(width 0)
				(type default)
			)
			(fill no)
			(layer "F.CrtYd")
		)
		(fp_rect
			(start -0.5842 1.3335)
			(end 0.5842 -1.3335)
			(stroke
				(width 0)
				(type default)
			)
			(fill no)
			(layer "F.Fab")
		)
		(pad "1" smd custom
			(at 0 -0.762 270)
			(size 0.2159 0.2159)
			(layers "F.Cu" "F.Mask" "F.Paste")
			(net "P0V9_E")
			(options
				(clearance outline)
				(anchor circle)
			)
			(primitives
				(gr_poly
					(pts
						(arc
							(start -0.3302 -0.4318)
							(mid -0.402042 -0.402042)
							(end -0.4318 -0.3302)
						)
						(arc
							(start -0.4318 0.3302)
							(mid -0.402042 0.402042)
							(end -0.3302 0.4318)
						)
						(arc
							(start 0.3302 0.4318)
							(mid 0.402042 0.402042)
							(end 0.4318 0.3302)
						)
						(arc
							(start 0.4318 -0.3302)
							(mid 0.402042 -0.402042)
							(end 0.3302 -0.4318)
						)
					)
					(width 0)
					(fill yes)
				)
			)
		)
		(pad "2" smd custom
			(at 0 0.762 270)
			(size 0.2159 0.2159)
			(layers "F.Cu" "F.Mask" "F.Paste")
			(net "GB_VDDA")
			(options
				(clearance outline)
				(anchor circle)
			)
			(primitives
				(gr_poly
					(pts
						(arc
							(start -0.3302 -0.4318)
							(mid -0.402042 -0.402042)
							(end -0.4318 -0.3302)
						)
						(arc
							(start -0.4318 0.3302)
							(mid -0.402042 0.402042)
							(end -0.3302 0.4318)
						)
						(arc
							(start 0.3302 0.4318)
							(mid 0.402042 0.402042)
							(end 0.4318 0.3302)
						)
						(arc
							(start 0.4318 -0.3302)
							(mid 0.402042 -0.402042)
							(end 0.3302 -0.4318)
						)
					)
					(width 0)
					(fill yes)
				)
			)
		)
	)
	(footprint ""
		(layer "F.Cu")
		(at 235.966 -15.113 -90)
		(property "Reference" "U38"
			(at 0 0 270)
			(layer "F.SilkS")
			(hide yes)
			(effects
				(font
					(size 1.27 1.27)
				)
			)
		)
		(property "Value" "SN74LVC1G08DCKR-GP"
			(at -2.3368 -8.6868 270)
			(unlocked yes)
			(layer "F.Fab")
			(hide yes)
			(effects
				(font
					(size 1.016 1.016)
					(thickness 0.1524)
				)
			)
		)
		(property "Device Type" "SC70-5H44"
			(at -2.3114 -10.414 270)
			(unlocked yes)
			(layer "F.Fab")
			(hide yes)
			(effects
				(font
					(size 1.016 1.016)
					(thickness 0.1524)
				)
			)
		)
		(duplicate_pad_numbers_are_jumpers no)
		(fp_line
			(start -1.27 1.7018)
			(end -1.27 -1.7018)
			(stroke
				(width 0.1524)
				(type default)
			)
			(layer "F.SilkS")
		)
		(fp_line
			(start 1.27 1.7018)
			(end -1.27 1.7018)
			(stroke
				(width 0.1524)
				(type default)
			)
			(layer "F.SilkS")
		)
		(fp_line
			(start -1.27 -1.7018)
			(end 1.27 -1.7018)
			(stroke
				(width 0.1524)
				(type default)
			)
			(layer "F.SilkS")
		)
		(fp_line
			(start 1.27 -1.7018)
			(end 1.27 1.7018)
			(stroke
				(width 0.1524)
				(type default)
			)
			(layer "F.SilkS")
		)
		(fp_line
			(start 0.6604 -1.8034)
			(end 1.3843 -1.8034)
			(stroke
				(width 0.3302)
				(type default)
			)
			(layer "F.SilkS")
		)
		(fp_line
			(start 1.3843 -1.8034)
			(end 1.3843 -1.1176)
			(stroke
				(width 0.3302)
				(type default)
			)
			(layer "F.SilkS")
		)
		(fp_rect
			(start -1.524 1.9558)
			(end 1.524 -1.9558)
			(stroke
				(width 0)
				(type default)
			)
			(fill no)
			(layer "F.CrtYd")
		)
		(fp_poly
			(pts
				(xy -1.524 -1.9558) (xy 1.524 -1.9558) (xy 1.524 1.9558) (xy -1.524 1.9558)
			)
			(stroke
				(width 0)
				(type default)
			)
			(fill no)
			(layer "F.Fab")
		)
		(pad "1" smd rect
			(at 0.65024 -0.8255 270)
			(size 0.4064 1.2192)
			(layers "F.Cu" "F.Mask" "F.Paste")
			(net "HB_OUT_R")
		)
		(pad "2" smd rect
			(at 0 -0.8255 270)
			(size 0.4064 1.2192)
			(layers "F.Cu" "F.Mask" "F.Paste")
			(net "BMC_ENCLOSURE_LED_R")
		)
		(pad "3" smd rect
			(at -0.65024 -0.8255 270)
			(size 0.4064 1.2192)
			(layers "F.Cu" "F.Mask" "F.Paste")
			(net "GND")
		)
		(pad "4" smd rect
			(at -0.65024 0.8255 270)
			(size 0.4064 1.2192)
			(layers "F.Cu" "F.Mask" "F.Paste")
			(net "ENCLO_LED_BLUE_OUT")
		)
		(pad "5" smd rect
			(at 0.65024 0.8255 270)
			(size 0.4064 1.2192)
			(layers "F.Cu" "F.Mask" "F.Paste")
			(net "P3V3_STBY")
		)
	)
)
